(kicad_pcb
	(version 20241229)
	(generator "pcbnew")
	(generator_version "9.0")
	(general
		(thickness 1.294)
		(legacy_teardrops no)
	)
	(paper "A3")
	(title_block
		(title "Kintex 410T devboard")
		(date "2024-04-03")
		(rev "1.1.2")
		(comment 9 "footprints 116-118 of 975")
	)
	(layers
		(0 "F.Cu" mixed)
		(4 "In1.Cu" power)
		(6 "In2.Cu" power)
		(8 "In3.Cu" mixed)
		(10 "In4.Cu" power)
		(12 "In5.Cu" mixed)
		(14 "In6.Cu" power)
		(16 "In7.Cu" mixed)
		(18 "In8.Cu" power)
		(2 "B.Cu" mixed)
		(9 "F.Adhes" user "F.Adhesive")
		(11 "B.Adhes" user "B.Adhesive")
		(13 "F.Paste" user)
		(15 "B.Paste" user)
		(5 "F.SilkS" user "F.Silkscreen")
		(7 "B.SilkS" user "B.Silkscreen")
		(1 "F.Mask" user)
		(3 "B.Mask" user)
		(17 "Dwgs.User" user "User.Drawings")
		(19 "Cmts.User" user "User.Comments")
		(21 "Eco1.User" user "User.Eco1")
		(23 "Eco2.User" user "User.Eco2")
		(25 "Edge.Cuts" user)
		(27 "Margin" user)
		(31 "F.CrtYd" user "F.Courtyard")
		(29 "B.CrtYd" user "B.Courtyard")
		(35 "F.Fab" user)
		(33 "B.Fab" user)
	)
	(footprint "antmicro-footprints:Resonator_SMD_Abracon_ABM8G_3.2x2.5mm"
		(layer "F.Cu")
		(at 196.701 103.099 90)
		(property "Reference" "Y1"
			(at 1.999 -0.701 0)
			(layer "F.SilkS")
			(effects
				(font
					(size 0.7 0.7)
					(thickness 0.15)
				)
				(justify left bottom)
			)
		)
		(property "Value" "Resonator_12MHz_ABM8G"
			(at -1.75 2.548 90)
			(layer "F.Fab")
			(effects
				(font
					(size 0.7 0.7)
					(thickness 0.15)
				)
				(justify left bottom)
			)
		)
		(property "Description" "Crystal, 12 MHz, SMT, 3.2mm x 2.5mm, 30 ppm, 18 pF, 20 ppm, ABM8G"
			(at 0 0 90)
			(layer "F.Fab")
			(hide yes)
			(effects
				(font
					(size 1.27 1.27)
					(thickness 0.15)
				)
			)
		)
		(property "Author" "Antmicro"
			(at 299.8 -93.602 0)
			(layer "F.Fab")
			(hide yes)
			(effects
				(font
					(size 1 1)
					(thickness 0.15)
				)
			)
		)
		(property "License" "Apache-2.0"
			(at 299.8 -93.602 0)
			(layer "F.Fab")
			(hide yes)
			(effects
				(font
					(size 1 1)
					(thickness 0.15)
				)
			)
		)
		(property "MPN" "ABM8G-12.000MHZ-18-D2Y-T"
			(at 299.8 -93.602 0)
			(layer "F.Fab")
			(hide yes)
			(effects
				(font
					(size 1 1)
					(thickness 0.15)
				)
			)
		)
		(property "Manufacturer" "Abracon"
			(at 299.8 -93.602 0)
			(layer "F.Fab")
			(hide yes)
			(effects
				(font
					(size 1 1)
					(thickness 0.15)
				)
			)
		)
		(property "Val" "12 MHz"
			(at 299.8 -93.602 0)
			(layer "F.Fab")
			(hide yes)
			(effects
				(font
					(size 1 1)
					(thickness 0.15)
				)
			)
		)
		(sheetname "USB PHY")
		(sheetfile "usb-phy.kicad_sch")
		(attr smd)
		(fp_line
			(start -0.35 -1.25)
			(end 0.45 -1.25)
			(stroke
				(width 0.15)
				(type solid)
			)
			(layer "F.SilkS")
		)
		(fp_line
			(start 1.6 0.3)
			(end 1.6 -0.2)
			(stroke
				(width 0.15)
				(type solid)
			)
			(layer "F.SilkS")
		)
		(fp_line
			(start -1.6 0.3)
			(end -1.6 -0.2)
			(stroke
				(width 0.15)
				(type solid)
			)
			(layer "F.SilkS")
		)
		(fp_line
			(start -0.35 1.25)
			(end 0.45 1.25)
			(stroke
				(width 0.15)
				(type solid)
			)
			(layer "F.SilkS")
		)
		(fp_circle
			(center -1.75 1.5)
			(end -1.7 1.5)
			(stroke
				(width 0.15)
				(type solid)
			)
			(fill no)
			(layer "F.SilkS")
		)
		(fp_rect
			(start -1.907 -1.55)
			(end 2.006 1.649)
			(stroke
				(width 0.05)
				(type solid)
			)
			(fill no)
			(layer "F.CrtYd")
		)
		(pad "1" smd roundrect
			(at -1.101 0.949 90)
			(size 1.3 1.1)
			(layers "F.Cu" "F.Mask" "F.Paste")
			(roundrect_rratio 0)
			(chamfer_ratio 0.2)
			(chamfer bottom_left)
			(net 706 "/USB PHY/USB_HOST_XI")
			(pintype "passive")
		)
		(pad "2" smd rect
			(at 1.199 0.949 90)
			(size 1.3 1.1)
			(layers "F.Cu" "F.Mask" "F.Paste")
			(net 1 "GND")
			(pinfunction "SH")
			(pintype "passive")
		)
		(pad "3" smd rect
			(at 1.199 -0.85 90)
			(size 1.3 1.1)
			(layers "F.Cu" "F.Mask" "F.Paste")
			(net 708 "/USB PHY/USB_HOST_XO")
			(pintype "passive")
		)
		(pad "4" smd rect
			(at -1.101 -0.85 90)
			(size 1.3 1.1)
			(layers "F.Cu" "F.Mask" "F.Paste")
			(net 1 "GND")
			(pinfunction "SH")
			(pintype "passive")
		)
	)
	(footprint "antmicro-footprints:C_0402_1005Metric"
		(layer "F.Cu")
		(at 244.6 141.6 90)
		(descr "Capacitor SMD 0402")
		(tags "capacitor SMD 0402")
		(property "Reference" "C225"
			(at -1.7 6.45 90)
			(layer "F.SilkS")
			(effects
				(font
					(size 0.7 0.7)
					(thickness 0.15)
				)
				(justify left bottom)
			)
		)
		(property "Value" "C_10u_0402"
			(at 0 1.4 90)
			(layer "F.Fab")
			(effects
				(font
					(size 0.7 0.7)
					(thickness 0.15)
				)
				(justify left bottom)
			)
		)
		(property "Description" "SMD Multilayer Ceramic Capacitor, 10 µF, 6.3 V, 0402 [1005 Metric], ± 20%, X5R, CC Series"
			(at 0 0 90)
			(layer "F.Fab")
			(hide yes)
			(effects
				(font
					(size 1.27 1.27)
					(thickness 0.15)
				)
			)
		)
		(property "Author" "Antmicro"
			(at 386.2 -103 0)
			(layer "F.Fab")
			(hide yes)
			(effects
				(font
					(size 1 1)
					(thickness 0.15)
				)
			)
		)
		(property "Dielectric" ""
			(at 386.2 -103 0)
			(layer "F.Fab")
			(hide yes)
			(effects
				(font
					(size 1 1)
					(thickness 0.15)
				)
			)
		)
		(property "License" "Apache-2.0"
			(at 386.2 -103 0)
			(layer "F.Fab")
			(hide yes)
			(effects
				(font
					(size 1 1)
					(thickness 0.15)
				)
			)
		)
		(property "MPN" "CC0402MRX5R5BB106"
			(at 386.2 -103 0)
			(layer "F.Fab")
			(hide yes)
			(effects
				(font
					(size 1 1)
					(thickness 0.15)
				)
			)
		)
		(property "Manufacturer" "YAGEO"
			(at 386.2 -103 0)
			(layer "F.Fab")
			(hide yes)
			(effects
				(font
					(size 1 1)
					(thickness 0.15)
				)
			)
		)
		(property "Val" "10u"
			(at 386.2 -103 0)
			(layer "F.Fab")
			(hide yes)
			(effects
				(font
					(size 1 1)
					(thickness 0.15)
				)
			)
		)
		(property "Voltage" ""
			(at 386.2 -103 0)
			(layer "F.Fab")
			(hide yes)
			(effects
				(font
					(size 1 1)
					(thickness 0.15)
				)
			)
		)
		(sheetname "USB PHY")
		(sheetfile "usb-phy.kicad_sch")
		(attr smd)
		(fp_rect
			(start -0.925 -0.47)
			(end 0.925 0.47)
			(stroke
				(width 0.05)
				(type default)
			)
			(fill no)
			(layer "F.CrtYd")
		)
		(fp_line
			(start 0.504 -0.25)
			(end 0.504 0.248)
			(stroke
				(width 0.15)
				(type solid)
			)
			(layer "F.Fab")
		)
		(fp_line
			(start -0.494 -0.25)
			(end 0.504 -0.25)
			(stroke
				(width 0.15)
				(type solid)
			)
			(layer "F.Fab")
		)
		(fp_line
			(start 0.504 0.248)
			(end -0.494 0.248)
			(stroke
				(width 0.15)
				(type solid)
			)
			(layer "F.Fab")
		)
		(fp_line
			(start -0.494 0.248)
			(end -0.494 -0.25)
			(stroke
				(width 0.15)
				(type solid)
			)
			(layer "F.Fab")
		)
		(pad "1" smd roundrect
			(at -0.48 0 90)
			(size 0.59 0.64)
			(layers "F.Cu" "F.Mask" "F.Paste")
			(roundrect_rratio 0.25)
			(net 1 "GND")
			(pintype "passive")
		)
		(pad "2" smd roundrect
			(at 0.48 0 90)
			(size 0.59 0.64)
			(layers "F.Cu" "F.Mask" "F.Paste")
			(roundrect_rratio 0.25)
			(net 707 "/USB PHY/FTDI_3V3")
			(pintype "passive")
		)
	)
	(footprint "antmicro-footprints:QFN-24-1EP_4x4mm_P0.5mm_EP2.6x2.6mm"
		(layer "F.Cu")
		(at 222.4 150.3 180)
		(descr "QFN, 24 Pin (http://ww1.microchip.com/downloads/en/PackagingSpec/00000049BQ.pdf#page=278), generated with kicad-footprint-generator ipc_noLead_generator.py")
		(tags "QFN NoLead")
		(property "Reference" "U26"
			(at 3.95 2.92 180)
			(layer "F.SilkS")
			(effects
				(font
					(size 0.7 0.7)
					(thickness 0.15)
				)
				(justify left bottom)
			)
		)
		(property "Value" "LAN8720A-CP-TR-ABC"
			(at 0 3.4 180)
			(layer "F.Fab")
			(effects
				(font
					(size 0.7 0.7)
					(thickness 0.15)
				)
				(justify left bottom)
			)
		)
		(property "Description" "Ethernet Controller, 100 Mbps, IEEE 802.3, IEEE 802.3u, 3 V, 3.6 V, SQFN, 24 Pins"
			(at 0 0 180)
			(layer "F.Fab")
			(hide yes)
			(effects
				(font
					(size 1.27 1.27)
					(thickness 0.15)
				)
			)
		)
		(property "Author" "Antmicro"
			(at 444.8 300.6 0)
			(layer "F.Fab")
			(hide yes)
			(effects
				(font
					(size 1 1)
					(thickness 0.15)
				)
			)
		)
		(property "License" "Apache-2.0"
			(at 444.8 300.6 0)
			(layer "F.Fab")
			(hide yes)
			(effects
				(font
					(size 1 1)
					(thickness 0.15)
				)
			)
		)
		(property "MPN" "LAN8720A-CP-TR-ABC"
			(at 444.8 300.6 0)
			(layer "F.Fab")
			(hide yes)
			(effects
				(font
					(size 1 1)
					(thickness 0.15)
				)
			)
		)
		(property "Manufacturer" "Microchip Technology"
			(at 444.8 300.6 0)
			(layer "F.Fab")
			(hide yes)
			(effects
				(font
					(size 1 1)
					(thickness 0.15)
				)
			)
		)
		(sheetname "HDMI + Ethernet")
		(sheetfile "hdmi-ethernet.kicad_sch")
		(attr smd)
		(fp_line
			(start 2.108 2.108)
			(end 2.108 1.634)
			(stroke
				(width 0.15)
				(type solid)
			)
			(layer "F.SilkS")
		)
		(fp_line
			(start 2.108 -2.11)
			(end 2.108 -1.635)
			(stroke
				(width 0.15)
				(type solid)
			)
			(layer "F.SilkS")
		)
		(fp_line
			(start 1.634 2.108)
			(end 2.108 2.108)
			(stroke
				(width 0.15)
				(type solid)
			)
			(layer "F.SilkS")
		)
		(fp_line
			(start 1.634 -2.11)
			(end 2.108 -2.11)
			(stroke
				(width 0.15)
				(type solid)
			)
			(layer "F.SilkS")
		)
		(fp_line
			(start -1.635 2.108)
			(end -2.11 2.108)
			(stroke
				(width 0.15)
				(type solid)
			)
			(layer "F.SilkS")
		)
		(fp_line
			(start -1.635 -2.11)
			(end -2.11 -2.11)
			(stroke
				(width 0.15)
				(type solid)
			)
			(layer "F.SilkS")
		)
		(fp_line
			(start -2.11 2.108)
			(end -2.11 1.634)
			(stroke
				(width 0.15)
				(type solid)
			)
			(layer "F.SilkS")
		)
		(fp_line
			(start -2.11 -1.636)
			(end -2.11 -2.11)
			(stroke
				(width 0.15)
				(type solid)
			)
			(layer "F.SilkS")
		)
		(fp_circle
			(center -2.3 -2.3)
			(end -2.25 -2.3)
			(stroke
				(width 0.15)
				(type solid)
			)
			(fill yes)
			(layer "F.SilkS")
		)
		(fp_rect
			(start -2.503 -2.503)
			(end 2.5 2.5)
			(stroke
				(width 0.05)
				(type solid)
			)
			(fill no)
			(layer "F.CrtYd")
		)
		(fp_line
			(start 1.999 1.999)
			(end -2 1.999)
			(stroke
				(width 0.15)
				(type solid)
			)
			(layer "F.Fab")
		)
		(fp_line
			(start 1.999 -2)
			(end 1.999 1.999)
			(stroke
				(width 0.15)
				(type solid)
			)
			(layer "F.Fab")
		)
		(fp_line
			(start -1 -2)
			(end 1.999 -2)
			(stroke
				(width 0.15)
				(type solid)
			)
			(layer "F.Fab")
		)
		(fp_line
			(start -2 1.999)
			(end -2 -1)
			(stroke
				(width 0.15)
				(type solid)
			)
			(layer "F.Fab")
		)
		(fp_line
			(start -2 -1)
			(end -1 -2)
			(stroke
				(width 0.15)
				(type solid)
			)
			(layer "F.Fab")
		)
		(pad "" smd roundrect
			(at -0.652 -0.652 180)
			(size 1.05 1.05)
			(layers "F.Paste")
			(roundrect_rratio 0.238095)
		)
		(pad "" smd roundrect
			(at -0.652 0.65 180)
			(size 1.05 1.05)
			(layers "F.Paste")
			(roundrect_rratio 0.238095)
		)
		(pad "" smd roundrect
			(at 0.65 -0.652 180)
			(size 1.05 1.05)
			(layers "F.Paste")
			(roundrect_rratio 0.238095)
		)
		(pad "" smd roundrect
			(at 0.65 0.65 180)
			(size 1.05 1.05)
			(layers "F.Paste")
			(roundrect_rratio 0.238095)
		)
		(pad "1" smd roundrect
			(at -1.938 -1.25 180)
			(size 0.825 0.25)
			(layers "F.Cu" "F.Mask" "F.Paste")
			(roundrect_rratio 0.25)
			(net 721 "/HDMI + Ethernet/ETH_3V3")
			(pinfunction "VDD2A")
			(pintype "power_in")
		)
		(pad "2" smd roundrect
			(at -1.938 -0.75 180)
			(size 0.825 0.25)
			(layers "F.Cu" "F.Mask" "F.Paste")
			(roundrect_rratio 0.25)
			(net 846 "/HDMI + Ethernet/ETH_LED_SPD-")
			(pinfunction "LED2/NINTSEL")
			(pintype "bidirectional")
		)
		(pad "3" smd roundrect
			(at -1.938 -0.25 180)
			(size 0.825 0.25)
			(layers "F.Cu" "F.Mask" "F.Paste")
			(roundrect_rratio 0.25)
			(net 847 "/HDMI + Ethernet/ETH_LED_LINK-")
			(pinfunction "LED1/REGOFF")
			(pintype "bidirectional")
		)
		(pad "4" smd roundrect
			(at -1.938 0.248 180)
			(size 0.825 0.25)
			(layers "F.Cu" "F.Mask" "F.Paste")
			(roundrect_rratio 0.25)
			(net 719 "/HDMI + Ethernet/ETH_XO")
			(pinfunction "XTAL2")
			(pintype "passive")
		)
		(pad "5" smd roundrect
			(at -1.938 0.748 180)
			(size 0.825 0.25)
			(layers "F.Cu" "F.Mask" "F.Paste")
			(roundrect_rratio 0.25)
			(net 716 "/HDMI + Ethernet/ETH_XI")
			(pinfunction "XTAL1/CLKIN")
			(pintype "passive")
		)
		(pad "6" smd roundrect
			(at -1.938 1.249 180)
			(size 0.825 0.25)
			(layers "F.Cu" "F.Mask" "F.Paste")
			(roundrect_rratio 0.25)
			(net 722 "/HDMI + Ethernet/ETH_VDDCR")
			(pinfunction "VDDCR")
			(pintype "power_in")
		)
		(pad "7" smd roundrect
			(at -1.25 1.937 180)
			(size 0.25 0.825)
			(layers "F.Cu" "F.Mask" "F.Paste")
			(roundrect_rratio 0.25)
			(net 945 "/HDMI + Ethernet/ETH_PHY_RXD1")
			(pinfunction "RXD1/MODE1")
			(pintype "output")
		)
		(pad "8" smd roundrect
			(at -0.75 1.937 180)
			(size 0.25 0.825)
			(layers "F.Cu" "F.Mask" "F.Paste")
			(roundrect_rratio 0.25)
			(net 946 "/HDMI + Ethernet/ETH_PHY_RXDO")
			(pinfunction "RXD0/MODE0")
			(pintype "output")
		)
		(pad "9" smd roundrect
			(at -0.25 1.937 180)
			(size 0.25 0.825)
			(layers "F.Cu" "F.Mask" "F.Paste")
			(roundrect_rratio 0.25)
			(net 26 "+1V8")
			(pinfunction "VDDIO")
			(pintype "power_in")
		)
		(pad "10" smd roundrect
			(at 0.248 1.937 180)
			(size 0.25 0.825)
			(layers "F.Cu" "F.Mask" "F.Paste")
			(roundrect_rratio 0.25)
			(net 947 "/HDMI + Ethernet/ETH_PHY_RXER")
			(pinfunction "RXER/PHYAD0")
			(pintype "output")
		)
		(pad "11" smd roundrect
			(at 0.748 1.937 180)
			(size 0.25 0.825)
			(layers "F.Cu" "F.Mask" "F.Paste")
			(roundrect_rratio 0.25)
			(net 944 "/HDMI + Ethernet/ETH_PHY_RX_DV")
			(pinfunction "CRS_DV/MODE2")
			(pintype "output")
		)
		(pad "12" smd roundrect
			(at 1.249 1.937 180)
			(size 0.25 0.825)
			(layers "F.Cu" "F.Mask" "F.Paste")
			(roundrect_rratio 0.25)
			(net 502 "/FPGA Bank 18 & 32/ETH_RMII.MDIO")
			(pinfunction "MDIO")
			(pintype "bidirectional")
		)
		(pad "13" smd roundrect
			(at 1.937 1.249 180)
			(size 0.825 0.25)
			(layers "F.Cu" "F.Mask" "F.Paste")
			(roundrect_rratio 0.25)
			(net 589 "/FPGA Bank 18 & 32/ETH_RMII.MDC")
			(pinfunction "MDC")
			(pintype "input")
		)
		(pad "14" smd roundrect
			(at 1.937 0.748 180)
			(size 0.825 0.25)
			(layers "F.Cu" "F.Mask" "F.Paste")
			(roundrect_rratio 0.25)
			(net 951 "/HDMI + Ethernet/ETH_PHY_REFCLK")
			(pinfunction "INT/REFCLKO")
			(pintype "output")
		)
		(pad "15" smd roundrect
			(at 1.937 0.248 180)
			(size 0.825 0.25)
			(layers "F.Cu" "F.Mask" "F.Paste")
			(roundrect_rratio 0.25)
			(net 501 "/FPGA Bank 18 & 32/ETH_RMII.~{RESET}")
			(pinfunction "RST")
			(pintype "input")
		)
		(pad "16" smd roundrect
			(at 1.937 -0.25 180)
			(size 0.825 0.25)
			(layers "F.Cu" "F.Mask" "F.Paste")
			(roundrect_rratio 0.25)
			(net 948 "/HDMI + Ethernet/ETH_PHY_TXEN")
			(pinfunction "TXEN")
			(pintype "input")
		)
		(pad "17" smd roundrect
			(at 1.937 -0.75 180)
			(size 0.825 0.25)
			(layers "F.Cu" "F.Mask" "F.Paste")
			(roundrect_rratio 0.25)
			(net 949 "/HDMI + Ethernet/ETH_PHY_TXDO")
			(pinfunction "TXD0")
			(pintype "input")
		)
		(pad "18" smd roundrect
			(at 1.937 -1.25 180)
			(size 0.825 0.25)
			(layers "F.Cu" "F.Mask" "F.Paste")
			(roundrect_rratio 0.25)
			(net 950 "/HDMI + Ethernet/ETH_PHY_TXD1")
			(pinfunction "TXD1")
			(pintype "input")
		)
		(pad "19" smd roundrect
			(at 1.249 -1.938 180)
			(size 0.25 0.825)
			(layers "F.Cu" "F.Mask" "F.Paste")
			(roundrect_rratio 0.25)
			(net 721 "/HDMI + Ethernet/ETH_3V3")
			(pinfunction "VDD1A")
			(pintype "power_in")
		)
		(pad "20" smd roundrect
			(at 0.748 -1.938 180)
			(size 0.25 0.825)
			(layers "F.Cu" "F.Mask" "F.Paste")
			(roundrect_rratio 0.25)
			(net 725 "/HDMI + Ethernet/ETH1_N")
			(pinfunction "TXN")
			(pintype "output")
		)
		(pad "21" smd roundrect
			(at 0.248 -1.938 180)
			(size 0.25 0.825)
			(layers "F.Cu" "F.Mask" "F.Paste")
			(roundrect_rratio 0.25)
			(net 724 "/HDMI + Ethernet/ETH1_P")
			(pinfunction "TXP")
			(pintype "output")
		)
		(pad "22" smd roundrect
			(at -0.25 -1.938 180)
			(size 0.25 0.825)
			(layers "F.Cu" "F.Mask" "F.Paste")
			(roundrect_rratio 0.25)
			(net 729 "/HDMI + Ethernet/ETH2_N")
			(pinfunction "RXN")
			(pintype "output")
		)
		(pad "23" smd roundrect
			(at -0.75 -1.938 180)
			(size 0.25 0.825)
			(layers "F.Cu" "F.Mask" "F.Paste")
			(roundrect_rratio 0.25)
			(net 726 "/HDMI + Ethernet/ETH2_P")
			(pinfunction "RXP")
			(pintype "output")
		)
		(pad "24" smd roundrect
			(at -1.25 -1.938 180)
			(size 0.25 0.825)
			(layers "F.Cu" "F.Mask" "F.Paste")
			(roundrect_rratio 0.25)
			(net 952 "/HDMI + Ethernet/ETH_ISET")
			(pinfunction "RBIAS")
			(pintype "input")
		)
		(pad "25" smd rect
			(at 0 0 180)
			(size 2.6 2.6)
			(layers "F.Cu" "F.Mask")
			(net 1 "GND")
			(pinfunction "VSS")
			(pintype "power_in")
		)
	)
)
